# T6G (Grand Teton) — schematic netlist excerpt (pin names and nets, part order shuffled) for the footprints in the layout excerpt that follows; sources: Cadence DE-HDL packaged netlist, KiCad conversion of 04192023_DAF0TMB3IC0_F0TG_MB_C_brd_V02_OCP.brd

PC464  Q_CAP  3300PF 50V 10% X7R  pkg 0402  page 193 : A = VSENSE_PVDDCR_SOC_P0_VSEN1 ; B = VSENSE_VSS_SENSE_A_P0
C2348  Q_CAP  22UF 4V 20% X6S  pkg C0402  page 73 : A = PVDDCR_CPU0_P1 ; B = GND

(kicad_pcb
	(version 20260206)
	(generator "pcbnew")
	(generator_version "10.0")
	(general
		(thickness 1.6)
		(legacy_teardrops no)
	)
	(paper "A4")
	(title_block
		(title "04192023_DAF0TMB3IC0_F0TG_MB_C_brd_V02_OCP.brd")
		(comment 1 "Grand Teton / footprints 7749-7750 of 8354")
	)
	(layers
		(0 "F.Cu" signal "TOP")
		(4 "In1.Cu" signal "GND")
		(6 "In2.Cu" signal "IN1")
		(8 "In3.Cu" signal "GND1")
		(10 "In4.Cu" signal "IN2")
		(12 "In5.Cu" signal "GND2")
		(14 "In6.Cu" signal "IN3")
		(16 "In7.Cu" signal "GND3")
		(18 "In8.Cu" signal "VCC")
		(20 "In9.Cu" signal "VCC1")
		(22 "In10.Cu" signal "GND4")
		(24 "In11.Cu" signal "IN4")
		(26 "In12.Cu" signal "GND5")
		(28 "In13.Cu" signal "IN5")
		(30 "In14.Cu" signal "GND6")
		(32 "In15.Cu" signal "IN6")
		(34 "In16.Cu" signal "GND7")
		(2 "B.Cu" signal "BOTTOM")
		(9 "F.Adhes" user "F.Adhesive")
		(11 "B.Adhes" user "B.Adhesive")
		(13 "F.Paste" user "Package Geometry/Pastemask Top")
		(15 "B.Paste" user "Package Geometry/Pastemask Bottom")
		(5 "F.SilkS" user "Ref Des/Silkscreen Top")
		(7 "B.SilkS" user "Ref Des/Silkscreen Bottom")
		(1 "F.Mask" user "Board Geometry/Soldermask Top")
		(3 "B.Mask" user "Board Geometry/Soldermask Bottom")
		(17 "Dwgs.User" user "User.Drawings")
		(19 "Cmts.User" user "User.Comments")
		(21 "Eco1.User" user "User.Eco1")
		(23 "Eco2.User" user "User.Eco2")
		(25 "Edge.Cuts" user "Board Geometry/Outline")
		(27 "Margin" user)
		(31 "F.CrtYd" user "Package Geometry/Place Bound Top")
		(29 "B.CrtYd" user "Package Geometry/Place Bound Bottom")
		(35 "F.Fab" user "Ref Des/Assembly Top")
		(33 "B.Fab" user "Ref Des/Assembly Bottom")
	)
	(footprint ""
		(layer "B.Cu")
		(at 383.732278 -144.647158 -90)
		(property "Reference" "PC464"
			(at 0 0 90)
			(layer "B.SilkS")
			(hide yes)
			(effects
				(font
					(size 1.27 1.27)
				)
				(justify mirror)
			)
		)
		(property "Value" ""
			(at 0 0 90)
			(layer "B.Fab")
			(effects
				(font
					(size 1.27 1.27)
				)
				(justify mirror)
			)
		)
		(duplicate_pad_numbers_are_jumpers no)
		(fp_line
			(start -0.7874 0.4064)
			(end 0.7874 0.4064)
			(stroke
				(width 0.1524)
				(type default)
			)
			(layer "B.SilkS")
		)
		(fp_line
			(start 0.7874 0.4064)
			(end 0.7874 -0.4064)
			(stroke
				(width 0.1524)
				(type default)
			)
			(layer "B.SilkS")
		)
		(fp_line
			(start -0.7874 -0.4064)
			(end -0.7874 0.4064)
			(stroke
				(width 0.1524)
				(type default)
			)
			(layer "B.SilkS")
		)
		(fp_line
			(start 0.7874 -0.4064)
			(end -0.7874 -0.4064)
			(stroke
				(width 0.1524)
				(type default)
			)
			(layer "B.SilkS")
		)
		(fp_line
			(start -0.67945 0.3048)
			(end -0.120396 0.3048)
			(stroke
				(width 0.1)
				(type default)
			)
			(layer "B.Fab")
		)
		(fp_line
			(start -0.120396 0.3048)
			(end -0.120396 0.2794)
			(stroke
				(width 0.1)
				(type default)
			)
			(layer "B.Fab")
		)
		(fp_line
			(start 0.12065 0.3048)
			(end 0.67945 0.3048)
			(stroke
				(width 0.1)
				(type default)
			)
			(layer "B.Fab")
		)
		(fp_line
			(start 0.67945 0.3048)
			(end 0.67945 -0.305054)
			(stroke
				(width 0.1)
				(type default)
			)
			(layer "B.Fab")
		)
		(fp_line
			(start -0.120396 0.2794)
			(end 0.12065 0.2794)
			(stroke
				(width 0.1)
				(type default)
			)
			(layer "B.Fab")
		)
		(fp_line
			(start 0.12065 0.2794)
			(end 0.12065 0.3048)
			(stroke
				(width 0.1)
				(type default)
			)
			(layer "B.Fab")
		)
		(fp_line
			(start -0.12065 -0.2794)
			(end -0.12065 -0.3048)
			(stroke
				(width 0.1)
				(type default)
			)
			(layer "B.Fab")
		)
		(fp_line
			(start 0.12065 -0.2794)
			(end -0.12065 -0.2794)
			(stroke
				(width 0.1)
				(type default)
			)
			(layer "B.Fab")
		)
		(fp_line
			(start -0.67945 -0.3048)
			(end -0.67945 0.3048)
			(stroke
				(width 0.1)
				(type default)
			)
			(layer "B.Fab")
		)
		(fp_line
			(start -0.12065 -0.3048)
			(end -0.67945 -0.3048)
			(stroke
				(width 0.1)
				(type default)
			)
			(layer "B.Fab")
		)
		(fp_line
			(start 0.12065 -0.305054)
			(end 0.12065 -0.2794)
			(stroke
				(width 0.1)
				(type default)
			)
			(layer "B.Fab")
		)
		(fp_line
			(start 0.67945 -0.305054)
			(end 0.12065 -0.305054)
			(stroke
				(width 0.1)
				(type default)
			)
			(layer "B.Fab")
		)
		(pad "1" smd circle
			(at 0.40005 0 90)
			(size 0 0)
			(layers "B.Cu" "B.Mask" "B.Paste")
			(net "VSENSE_PVDDCR_SOC_P0_VSEN1")
		)
		(pad "2" smd circle
			(at -0.40005 0 90)
			(size 0 0)
			(layers "B.Cu" "B.Mask" "B.Paste")
			(net "VSENSE_VSS_SENSE_A_P0")
		)
	)
	(footprint ""
		(layer "B.Cu")
		(at 102.938834 -250.892564 180)
		(property "Reference" "C2348"
			(at 0 0 0)
			(layer "B.SilkS")
			(hide yes)
			(effects
				(font
					(size 1.27 1.27)
				)
				(justify mirror)
			)
		)
		(property "Value" ""
			(at 0 0 0)
			(layer "B.Fab")
			(effects
				(font
					(size 1.27 1.27)
				)
				(justify mirror)
			)
		)
		(duplicate_pad_numbers_are_jumpers no)
		(fp_line
			(start 0.7874 0.4064)
			(end 0.7874 -0.4064)
			(stroke
				(width 0.1524)
				(type default)
			)
			(layer "B.SilkS")
		)
		(fp_line
			(start 0.7874 -0.4064)
			(end -0.7874 -0.4064)
			(stroke
				(width 0.1524)
				(type default)
			)
			(layer "B.SilkS")
		)
		(fp_line
			(start -0.7874 0.4064)
			(end 0.7874 0.4064)
			(stroke
				(width 0.1524)
				(type default)
			)
			(layer "B.SilkS")
		)
		(fp_line
			(start -0.7874 -0.4064)
			(end -0.7874 0.4064)
			(stroke
				(width 0.1524)
				(type default)
			)
			(layer "B.SilkS")
		)
		(fp_line
			(start 0.67945 0.3048)
			(end 0.67945 -0.305054)
			(stroke
				(width 0.1)
				(type default)
			)
			(layer "B.Fab")
		)
		(fp_line
			(start 0.67945 -0.305054)
			(end 0.12065 -0.305054)
			(stroke
				(width 0.1)
				(type default)
			)
			(layer "B.Fab")
		)
		(fp_line
			(start 0.12065 0.3048)
			(end 0.67945 0.3048)
			(stroke
				(width 0.1)
				(type default)
			)
			(layer "B.Fab")
		)
		(fp_line
			(start 0.12065 0.2794)
			(end 0.12065 0.3048)
			(stroke
				(width 0.1)
				(type default)
			)
			(layer "B.Fab")
		)
		(fp_line
			(start 0.12065 -0.2794)
			(end -0.12065 -0.2794)
			(stroke
				(width 0.1)
				(type default)
			)
			(layer "B.Fab")
		)
		(fp_line
			(start 0.12065 -0.305054)
			(end 0.12065 -0.2794)
			(stroke
				(width 0.1)
				(type default)
			)
			(layer "B.Fab")
		)
		(fp_line
			(start -0.120396 0.3048)
			(end -0.120396 0.2794)
			(stroke
				(width 0.1)
				(type default)
			)
			(layer "B.Fab")
		)
		(fp_line
			(start -0.120396 0.2794)
			(end 0.12065 0.2794)
			(stroke
				(width 0.1)
				(type default)
			)
			(layer "B.Fab")
		)
		(fp_line
			(start -0.12065 -0.2794)
			(end -0.12065 -0.3048)
			(stroke
				(width 0.1)
				(type default)
			)
			(layer "B.Fab")
		)
		(fp_line
			(start -0.12065 -0.3048)
			(end -0.67945 -0.3048)
			(stroke
				(width 0.1)
				(type default)
			)
			(layer "B.Fab")
		)
		(fp_line
			(start -0.67945 0.3048)
			(end -0.120396 0.3048)
			(stroke
				(width 0.1)
				(type default)
			)
			(layer "B.Fab")
		)
		(fp_line
			(start -0.67945 -0.3048)
			(end -0.67945 0.3048)
			(stroke
				(width 0.1)
				(type default)
			)
			(layer "B.Fab")
		)
		(pad "1" smd circle
			(at 0.40005 0)
			(size 0 0)
			(layers "B.Cu" "B.Mask" "B.Paste")
			(net "PVDDCR_CPU0_P1")
		)
		(pad "2" smd circle
			(at -0.40005 0)
			(size 0 0)
			(layers "B.Cu" "B.Mask" "B.Paste")
			(net "GND")
		)
	)
)
